(kicad_pcb
	(version 20260206)
	(generator "pcbnew")
	(generator_version "10.0")
	(general
		(thickness 1.6)
		(legacy_teardrops no)
	)
	(paper "A4")
	(title_block
		(title "v2-tray-backplane — ms_tbp_v2.brd")
		(comment 1 "Open CloudServer (Microsoft) / footprint 52 of 164 (J13), pads 1-95 of 155")
	)
	(layers
		(0 "F.Cu" signal "TOP")
		(4 "In1.Cu" signal "LYR2")
		(6 "In2.Cu" signal "LYR3")
		(8 "In3.Cu" signal "LYR4")
		(10 "In4.Cu" signal "LYR5")
		(12 "In5.Cu" signal "LYR6")
		(14 "In6.Cu" signal "LYR7")
		(2 "B.Cu" signal "BOTTOM")
		(9 "F.Adhes" user "F.Adhesive")
		(11 "B.Adhes" user "B.Adhesive")
		(13 "F.Paste" user "Package Geometry/Pastemask Top")
		(15 "B.Paste" user "Package Geometry/Pastemask Bottom")
		(5 "F.SilkS" user "Ref Des/Silkscreen Top")
		(7 "B.SilkS" user "Ref Des/Silkscreen Bottom")
		(1 "F.Mask" user "Board Geometry/Soldermask Top")
		(3 "B.Mask" user "Board Geometry/Soldermask Bottom")
		(17 "Dwgs.User" user "User.Drawings")
		(19 "Cmts.User" user "User.Comments")
		(21 "Eco1.User" user "User.Eco1")
		(23 "Eco2.User" user "User.Eco2")
		(25 "Edge.Cuts" user "Board Geometry/Outline")
		(27 "Margin" user)
		(31 "F.CrtYd" user "Package Geometry/Place Bound Top")
		(29 "B.CrtYd" user "Package Geometry/Place Bound Bottom")
		(35 "F.Fab" user "Ref Des/Assembly Top")
		(33 "B.Fab" user "Ref Des/Assembly Bottom")
	)
	(footprint ""
		(layer "F.Cu")
		(at -171.46 45.260001 180)
		(property "Reference" "J13"
			(at 9.007 25.028901 0)
			(unlocked yes)
			(layer "F.SilkS")
			(effects
				(font
					(size 0.762 0.5334)
					(thickness 0.1016)
				)
			)
		)
		(property "Value" ""
			(at 0 0 180)
			(layer "F.Fab")
			(effects
				(font
					(size 1.27 1.27)
				)
			)
		)
		(duplicate_pad_numbers_are_jumpers no)
		(pad "A1" thru_hole rect
			(at 0 0 180)
			(size 0.8128 0.8128)
			(drill 0.508)
			(layers "*.Cu" "*.Mask")
			(remove_unused_layers no)
			(net "PCIE_T2B_B2_RX_DP<7>")
			(padstack
				(mode front_inner_back)
				(layer "Inner"
					(shape circle)
					(size 0.8128 0.8128)
				)
				(layer "B.Cu"
					(shape rect)
					(size 0.8128 0.8128)
				)
			)
		)
		(pad "A2" thru_hole circle
			(at 2.000001 -0.1 180)
			(size 0.8128 0.8128)
			(drill 0.508)
			(layers "*.Cu" "*.Mask")
			(remove_unused_layers no)
			(net "GND")
		)
		(pad "A3" thru_hole circle
			(at 4 0 180)
			(size 0.8128 0.8128)
			(drill 0.508)
			(layers "*.Cu" "*.Mask")
			(remove_unused_layers no)
			(net "PCIE_T2B_B2_RX_DP<5>")
		)
		(pad "A4" thru_hole circle
			(at 6.000001 -0.1 180)
			(size 0.8128 0.8128)
			(drill 0.508)
			(layers "*.Cu" "*.Mask")
			(remove_unused_layers no)
			(net "GND")
		)
		(pad "A5" thru_hole circle
			(at 7.999999 0 180)
			(size 0.8128 0.8128)
			(drill 0.508)
			(layers "*.Cu" "*.Mask")
			(remove_unused_layers no)
			(net "PCIE_T2B_B2_RX_DP<3>")
		)
		(pad "A6" thru_hole circle
			(at 10 -0.1 180)
			(size 0.8128 0.8128)
			(drill 0.508)
			(layers "*.Cu" "*.Mask")
			(remove_unused_layers no)
			(net "GND")
		)
		(pad "A7" thru_hole circle
			(at 11.999999 0 180)
			(size 0.8128 0.8128)
			(drill 0.508)
			(layers "*.Cu" "*.Mask")
			(remove_unused_layers no)
			(net "PCIE_T2B_B2_RX_DP<1>")
		)
		(pad "A8" thru_hole circle
			(at 14 -0.1 180)
			(size 0.8128 0.8128)
			(drill 0.508)
			(layers "*.Cu" "*.Mask")
			(remove_unused_layers no)
			(net "GND")
		)
		(pad "A9" thru_hole circle
			(at 16.000001 0 180)
			(size 0.8128 0.8128)
			(drill 0.508)
			(layers "*.Cu" "*.Mask")
			(remove_unused_layers no)
			(net "CLK_100M_B2_P<0>")
		)
		(pad "A10" thru_hole circle
			(at 18 -0.1 180)
			(size 0.8128 0.8128)
			(drill 0.508)
			(layers "*.Cu" "*.Mask")
			(remove_unused_layers no)
			(net "GND")
		)
		(pad "B1" thru_hole circle
			(at 0 1.4 180)
			(size 0.8128 0.8128)
			(drill 0.508)
			(layers "*.Cu" "*.Mask")
			(remove_unused_layers no)
			(net "PCIE_T2B_B2_RX_DN<7>")
		)
		(pad "B2" thru_hole circle
			(at 2.000001 1.3 180)
			(size 0.8128 0.8128)
			(drill 0.508)
			(layers "*.Cu" "*.Mask")
			(remove_unused_layers no)
			(net "PCIE_T2B_B2_RX_DP<6>")
		)
		(pad "B3" thru_hole circle
			(at 4 1.4 180)
			(size 0.8128 0.8128)
			(drill 0.508)
			(layers "*.Cu" "*.Mask")
			(remove_unused_layers no)
			(net "PCIE_T2B_B2_RX_DN<5>")
		)
		(pad "B4" thru_hole circle
			(at 6.000001 1.3 180)
			(size 0.8128 0.8128)
			(drill 0.508)
			(layers "*.Cu" "*.Mask")
			(remove_unused_layers no)
			(net "PCIE_T2B_B2_RX_DP<4>")
		)
		(pad "B5" thru_hole circle
			(at 7.999999 1.4 180)
			(size 0.8128 0.8128)
			(drill 0.508)
			(layers "*.Cu" "*.Mask")
			(remove_unused_layers no)
			(net "PCIE_T2B_B2_RX_DN<3>")
		)
		(pad "B6" thru_hole circle
			(at 10 1.3 180)
			(size 0.8128 0.8128)
			(drill 0.508)
			(layers "*.Cu" "*.Mask")
			(remove_unused_layers no)
			(net "PCIE_T2B_B2_RX_DP<2>")
		)
		(pad "B7" thru_hole circle
			(at 11.999999 1.4 180)
			(size 0.8128 0.8128)
			(drill 0.508)
			(layers "*.Cu" "*.Mask")
			(remove_unused_layers no)
			(net "PCIE_T2B_B2_RX_DN<1>")
		)
		(pad "B8" thru_hole circle
			(at 14 1.3 180)
			(size 0.8128 0.8128)
			(drill 0.508)
			(layers "*.Cu" "*.Mask")
			(remove_unused_layers no)
			(net "PCIE_T2B_B2_RX_DP<0>")
		)
		(pad "B9" thru_hole circle
			(at 16.000001 1.4 180)
			(size 0.8128 0.8128)
			(drill 0.508)
			(layers "*.Cu" "*.Mask")
			(remove_unused_layers no)
			(net "CLK_100M_B2_N<0>")
		)
		(pad "B10" thru_hole circle
			(at 18 1.3 180)
			(size 0.8128 0.8128)
			(drill 0.508)
			(layers "*.Cu" "*.Mask")
			(remove_unused_layers no)
			(net "USB_B2_P")
		)
		(pad "C1" thru_hole circle
			(at 0 2.799999 180)
			(size 0.8128 0.8128)
			(drill 0.508)
			(layers "*.Cu" "*.Mask")
			(remove_unused_layers no)
			(net "GND")
		)
		(pad "C2" thru_hole circle
			(at 2.000001 2.7 180)
			(size 0.8128 0.8128)
			(drill 0.508)
			(layers "*.Cu" "*.Mask")
			(remove_unused_layers no)
			(net "PCIE_T2B_B2_RX_DN<6>")
		)
		(pad "C3" thru_hole circle
			(at 4 2.799999 180)
			(size 0.8128 0.8128)
			(drill 0.508)
			(layers "*.Cu" "*.Mask")
			(remove_unused_layers no)
			(net "GND")
		)
		(pad "C4" thru_hole circle
			(at 6.000001 2.7 180)
			(size 0.8128 0.8128)
			(drill 0.508)
			(layers "*.Cu" "*.Mask")
			(remove_unused_layers no)
			(net "PCIE_T2B_B2_RX_DN<4>")
		)
		(pad "C5" thru_hole circle
			(at 7.999999 2.799999 180)
			(size 0.8128 0.8128)
			(drill 0.508)
			(layers "*.Cu" "*.Mask")
			(remove_unused_layers no)
			(net "GND")
		)
		(pad "C6" thru_hole circle
			(at 10 2.7 180)
			(size 0.8128 0.8128)
			(drill 0.508)
			(layers "*.Cu" "*.Mask")
			(remove_unused_layers no)
			(net "PCIE_T2B_B2_RX_DN<2>")
		)
		(pad "C7" thru_hole circle
			(at 11.999999 2.799999 180)
			(size 0.8128 0.8128)
			(drill 0.508)
			(layers "*.Cu" "*.Mask")
			(remove_unused_layers no)
			(net "GND")
		)
		(pad "C8" thru_hole circle
			(at 14 2.7 180)
			(size 0.8128 0.8128)
			(drill 0.508)
			(layers "*.Cu" "*.Mask")
			(remove_unused_layers no)
			(net "PCIE_T2B_B2_RX_DN<0>")
		)
		(pad "C9" thru_hole circle
			(at 16.000001 2.799999 180)
			(size 0.8128 0.8128)
			(drill 0.508)
			(layers "*.Cu" "*.Mask")
			(remove_unused_layers no)
			(net "GND")
		)
		(pad "C10" thru_hole circle
			(at 18 2.7 180)
			(size 0.8128 0.8128)
			(drill 0.508)
			(layers "*.Cu" "*.Mask")
			(remove_unused_layers no)
			(net "USB_B2_N")
		)
		(pad "D1" thru_hole circle
			(at 0 4.199999 180)
			(size 0.8128 0.8128)
			(drill 0.508)
			(layers "*.Cu" "*.Mask")
			(remove_unused_layers no)
			(net "PCIE_T2B_B2_RX_DP<15>")
		)
		(pad "D2" thru_hole circle
			(at 2.000001 4.099999 180)
			(size 0.8128 0.8128)
			(drill 0.508)
			(layers "*.Cu" "*.Mask")
			(remove_unused_layers no)
			(net "GND")
		)
		(pad "D3" thru_hole circle
			(at 4 4.199999 180)
			(size 0.8128 0.8128)
			(drill 0.508)
			(layers "*.Cu" "*.Mask")
			(remove_unused_layers no)
			(net "PCIE_T2B_B2_RX_DP<13>")
		)
		(pad "D4" thru_hole circle
			(at 6.000001 4.099999 180)
			(size 0.8128 0.8128)
			(drill 0.508)
			(layers "*.Cu" "*.Mask")
			(remove_unused_layers no)
			(net "GND")
		)
		(pad "D5" thru_hole circle
			(at 7.999999 4.199999 180)
			(size 0.8128 0.8128)
			(drill 0.508)
			(layers "*.Cu" "*.Mask")
			(remove_unused_layers no)
			(net "PCIE_T2B_B2_RX_DP<11>")
		)
		(pad "D6" thru_hole circle
			(at 10 4.099999 180)
			(size 0.8128 0.8128)
			(drill 0.508)
			(layers "*.Cu" "*.Mask")
			(remove_unused_layers no)
			(net "GND")
		)
		(pad "D7" thru_hole circle
			(at 11.999999 4.199999 180)
			(size 0.8128 0.8128)
			(drill 0.508)
			(layers "*.Cu" "*.Mask")
			(remove_unused_layers no)
			(net "PCIE_T2B_B2_RX_DP<9>")
		)
		(pad "D8" thru_hole circle
			(at 14 4.099999 180)
			(size 0.8128 0.8128)
			(drill 0.508)
			(layers "*.Cu" "*.Mask")
			(remove_unused_layers no)
			(net "GND")
		)
		(pad "D9" thru_hole circle
			(at 16.000001 4.199999 180)
			(size 0.8128 0.8128)
			(drill 0.508)
			(layers "*.Cu" "*.Mask")
			(remove_unused_layers no)
			(net "CLK_100M_B2_P<1>")
		)
		(pad "D10" thru_hole circle
			(at 18 4.099999 180)
			(size 0.8128 0.8128)
			(drill 0.508)
			(layers "*.Cu" "*.Mask")
			(remove_unused_layers no)
			(net "GND")
		)
		(pad "E1" thru_hole circle
			(at 0 5.599999 180)
			(size 0.8128 0.8128)
			(drill 0.508)
			(layers "*.Cu" "*.Mask")
			(remove_unused_layers no)
			(net "PCIE_T2B_B2_RX_DN<15>")
		)
		(pad "E2" thru_hole circle
			(at 2.000001 5.499999 180)
			(size 0.8128 0.8128)
			(drill 0.508)
			(layers "*.Cu" "*.Mask")
			(remove_unused_layers no)
			(net "PCIE_T2B_B2_RX_DP<14>")
		)
		(pad "E3" thru_hole circle
			(at 4 5.599999 180)
			(size 0.8128 0.8128)
			(drill 0.508)
			(layers "*.Cu" "*.Mask")
			(remove_unused_layers no)
			(net "PCIE_T2B_B2_RX_DN<13>")
		)
		(pad "E4" thru_hole circle
			(at 6.000001 5.499999 180)
			(size 0.8128 0.8128)
			(drill 0.508)
			(layers "*.Cu" "*.Mask")
			(remove_unused_layers no)
			(net "PCIE_T2B_B2_RX_DP<12>")
		)
		(pad "E5" thru_hole circle
			(at 7.999999 5.599999 180)
			(size 0.8128 0.8128)
			(drill 0.508)
			(layers "*.Cu" "*.Mask")
			(remove_unused_layers no)
			(net "PCIE_T2B_B2_RX_DN<11>")
		)
		(pad "E6" thru_hole circle
			(at 10 5.499999 180)
			(size 0.8128 0.8128)
			(drill 0.508)
			(layers "*.Cu" "*.Mask")
			(remove_unused_layers no)
			(net "PCIE_T2B_B2_RX_DP<10>")
		)
		(pad "E7" thru_hole circle
			(at 11.999999 5.599999 180)
			(size 0.8128 0.8128)
			(drill 0.508)
			(layers "*.Cu" "*.Mask")
			(remove_unused_layers no)
			(net "PCIE_T2B_B2_RX_DN<9>")
		)
		(pad "E8" thru_hole circle
			(at 14 5.499999 180)
			(size 0.8128 0.8128)
			(drill 0.508)
			(layers "*.Cu" "*.Mask")
			(remove_unused_layers no)
			(net "PCIE_T2B_B2_RX_DP<8>")
		)
		(pad "E9" thru_hole circle
			(at 16.000001 5.599999 180)
			(size 0.8128 0.8128)
			(drill 0.508)
			(layers "*.Cu" "*.Mask")
			(remove_unused_layers no)
			(net "CLK_100M_B2_N<1>")
		)
		(pad "E10" thru_hole circle
			(at 18 5.499999 180)
			(size 0.8128 0.8128)
			(drill 0.508)
			(layers "*.Cu" "*.Mask")
			(remove_unused_layers no)
			(net "P5V_USB_B2")
		)
		(pad "F1" thru_hole circle
			(at 0 7.000001 180)
			(size 0.8128 0.8128)
			(drill 0.508)
			(layers "*.Cu" "*.Mask")
			(remove_unused_layers no)
			(net "GND")
		)
		(pad "F2" thru_hole circle
			(at 2.000001 6.899999 180)
			(size 0.8128 0.8128)
			(drill 0.508)
			(layers "*.Cu" "*.Mask")
			(remove_unused_layers no)
			(net "PCIE_T2B_B2_RX_DN<14>")
		)
		(pad "F3" thru_hole circle
			(at 4 7.000001 180)
			(size 0.8128 0.8128)
			(drill 0.508)
			(layers "*.Cu" "*.Mask")
			(remove_unused_layers no)
			(net "GND")
		)
		(pad "F4" thru_hole circle
			(at 6.000001 6.899999 180)
			(size 0.8128 0.8128)
			(drill 0.508)
			(layers "*.Cu" "*.Mask")
			(remove_unused_layers no)
			(net "PCIE_T2B_B2_RX_DN<12>")
		)
		(pad "F5" thru_hole circle
			(at 7.999999 7.000001 180)
			(size 0.8128 0.8128)
			(drill 0.508)
			(layers "*.Cu" "*.Mask")
			(remove_unused_layers no)
			(net "GND")
		)
		(pad "F6" thru_hole circle
			(at 10 6.899999 180)
			(size 0.8128 0.8128)
			(drill 0.508)
			(layers "*.Cu" "*.Mask")
			(remove_unused_layers no)
			(net "PCIE_T2B_B2_RX_DN<10>")
		)
		(pad "F7" thru_hole circle
			(at 11.999999 7.000001 180)
			(size 0.8128 0.8128)
			(drill 0.508)
			(layers "*.Cu" "*.Mask")
			(remove_unused_layers no)
			(net "GND")
		)
		(pad "F8" thru_hole circle
			(at 14 6.899999 180)
			(size 0.8128 0.8128)
			(drill 0.508)
			(layers "*.Cu" "*.Mask")
			(remove_unused_layers no)
			(net "PCIE_T2B_B2_RX_DN<8>")
		)
		(pad "F9" thru_hole circle
			(at 16.000001 7.000001 180)
			(size 0.8128 0.8128)
			(drill 0.508)
			(layers "*.Cu" "*.Mask")
			(remove_unused_layers no)
			(net "GND")
		)
		(pad "F10" thru_hole circle
			(at 18 6.899999 180)
			(size 0.8128 0.8128)
			(drill 0.508)
			(layers "*.Cu" "*.Mask")
			(remove_unused_layers no)
			(net "GND")
		)
		(pad "G1" thru_hole circle
			(at 0 8.400001 180)
			(size 0.8128 0.8128)
			(drill 0.508)
			(layers "*.Cu" "*.Mask")
			(remove_unused_layers no)
			(net "PCIE_RESET_B2_N<3>")
		)
		(pad "G2" thru_hole circle
			(at 2.000001 8.300001 180)
			(size 0.8128 0.8128)
			(drill 0.508)
			(layers "*.Cu" "*.Mask")
			(remove_unused_layers no)
			(net "GND")
		)
		(pad "G3" thru_hole circle
			(at 4 8.400001 180)
			(size 0.8128 0.8128)
			(drill 0.508)
			(layers "*.Cu" "*.Mask")
			(remove_unused_layers no)
			(net "PCIE_CFG_B2_ID0")
		)
		(pad "G4" thru_hole circle
			(at 6.000001 8.300001 180)
			(size 0.8128 0.8128)
			(drill 0.508)
			(layers "*.Cu" "*.Mask")
			(remove_unused_layers no)
			(net "GND")
		)
		(pad "G5" thru_hole circle
			(at 7.999999 8.400001 180)
			(size 0.8128 0.8128)
			(drill 0.508)
			(layers "*.Cu" "*.Mask")
			(remove_unused_layers no)
			(net "MEZZ_B2_SCL")
		)
		(pad "G6" thru_hole circle
			(at 10 8.300001 180)
			(size 0.8128 0.8128)
			(drill 0.508)
			(layers "*.Cu" "*.Mask")
			(remove_unused_layers no)
			(net "GND")
		)
		(pad "G7" thru_hole circle
			(at 11.999999 8.400001 180)
			(size 0.8128 0.8128)
			(drill 0.508)
			(layers "*.Cu" "*.Mask")
			(remove_unused_layers no)
			(net "Net_2")
		)
		(pad "G8" thru_hole circle
			(at 14 8.300001 180)
			(size 0.8128 0.8128)
			(drill 0.508)
			(layers "*.Cu" "*.Mask")
			(remove_unused_layers no)
			(net "GND")
		)
		(pad "G9" thru_hole circle
			(at 16.000001 8.400001 180)
			(size 0.8128 0.8128)
			(drill 0.508)
			(layers "*.Cu" "*.Mask")
			(remove_unused_layers no)
			(net "CLK_100M_B2_P<2>")
		)
		(pad "G10" thru_hole circle
			(at 18 8.300001 180)
			(size 0.8128 0.8128)
			(drill 0.508)
			(layers "*.Cu" "*.Mask")
			(remove_unused_layers no)
			(net "GND")
		)
		(pad "H1" thru_hole circle
			(at 0 9.800001 180)
			(size 0.8128 0.8128)
			(drill 0.508)
			(layers "*.Cu" "*.Mask")
			(remove_unused_layers no)
			(net "PCIE_RESET_B2_N<2>")
		)
		(pad "H2" thru_hole circle
			(at 2.000001 9.700001 180)
			(size 0.8128 0.8128)
			(drill 0.508)
			(layers "*.Cu" "*.Mask")
			(remove_unused_layers no)
			(net "PCIE_RESET_B2_N<1>")
		)
		(pad "H3" thru_hole circle
			(at 4 9.800001 180)
			(size 0.8128 0.8128)
			(drill 0.508)
			(layers "*.Cu" "*.Mask")
			(remove_unused_layers no)
			(net "PCIE_CFG_B2_ID1")
		)
		(pad "H4" thru_hole circle
			(at 6.000001 9.700001 180)
			(size 0.8128 0.8128)
			(drill 0.508)
			(layers "*.Cu" "*.Mask")
			(remove_unused_layers no)
			(net "PCIE_WAKE_B2_N")
		)
		(pad "H5" thru_hole circle
			(at 7.999999 9.800001 180)
			(size 0.8128 0.8128)
			(drill 0.508)
			(layers "*.Cu" "*.Mask")
			(remove_unused_layers no)
			(net "MEZZ_B2_EN")
		)
		(pad "H6" thru_hole circle
			(at 10 9.700001 180)
			(size 0.8128 0.8128)
			(drill 0.508)
			(layers "*.Cu" "*.Mask")
			(remove_unused_layers no)
			(net "MEZZ_PRESENT_B2_N")
		)
		(pad "H7" thru_hole circle
			(at 11.999999 9.800001 180)
			(size 0.8128 0.8128)
			(drill 0.508)
			(layers "*.Cu" "*.Mask")
			(remove_unused_layers no)
			(net "PSU_B2_ALERT_N")
		)
		(pad "H8" thru_hole circle
			(at 14 9.700001 180)
			(size 0.8128 0.8128)
			(drill 0.508)
			(layers "*.Cu" "*.Mask")
			(remove_unused_layers no)
			(net "SERIAL_B2_TX2")
		)
		(pad "H9" thru_hole circle
			(at 16.000001 9.800001 180)
			(size 0.8128 0.8128)
			(drill 0.508)
			(layers "*.Cu" "*.Mask")
			(remove_unused_layers no)
			(net "CLK_100M_B2_N<2>")
		)
		(pad "H10" thru_hole circle
			(at 18 9.700001 180)
			(size 0.8128 0.8128)
			(drill 0.508)
			(layers "*.Cu" "*.Mask")
			(remove_unused_layers no)
			(net "GND")
		)
		(pad "I1" thru_hole circle
			(at 0 11.2 180)
			(size 0.8128 0.8128)
			(drill 0.508)
			(layers "*.Cu" "*.Mask")
			(remove_unused_layers no)
			(net "GND")
		)
		(pad "I2" thru_hole circle
			(at 2.000001 11.100001 180)
			(size 0.8128 0.8128)
			(drill 0.508)
			(layers "*.Cu" "*.Mask")
			(remove_unused_layers no)
			(net "PCIE_RESET_B2_N<0>")
		)
		(pad "I3" thru_hole circle
			(at 4 11.2 180)
			(size 0.8128 0.8128)
			(drill 0.508)
			(layers "*.Cu" "*.Mask")
			(remove_unused_layers no)
			(net "GND")
		)
		(pad "I4" thru_hole circle
			(at 6.000001 11.100001 180)
			(size 0.8128 0.8128)
			(drill 0.508)
			(layers "*.Cu" "*.Mask")
			(remove_unused_layers no)
			(net "MEZZ_B2_SDA")
		)
		(pad "I5" thru_hole circle
			(at 7.999999 11.2 180)
			(size 0.8128 0.8128)
			(drill 0.508)
			(layers "*.Cu" "*.Mask")
			(remove_unused_layers no)
			(net "GND")
		)
		(pad "I6" thru_hole circle
			(at 10 11.100001 180)
			(size 0.8128 0.8128)
			(drill 0.508)
			(layers "*.Cu" "*.Mask")
			(remove_unused_layers no)
			(net "BLADE_MATED_B2_N<0>")
		)
		(pad "I7" thru_hole circle
			(at 11.999999 11.2 180)
			(size 0.8128 0.8128)
			(drill 0.508)
			(layers "*.Cu" "*.Mask")
			(remove_unused_layers no)
			(net "GND")
		)
		(pad "I8" thru_hole circle
			(at 14 11.100001 180)
			(size 0.8128 0.8128)
			(drill 0.508)
			(layers "*.Cu" "*.Mask")
			(remove_unused_layers no)
			(net "SERIAL_B2_RX2")
		)
		(pad "I9" thru_hole circle
			(at 16.000001 11.2 180)
			(size 0.8128 0.8128)
			(drill 0.508)
			(layers "*.Cu" "*.Mask")
			(remove_unused_layers no)
			(net "GND")
		)
		(pad "I10" thru_hole circle
			(at 18 11.100001 180)
			(size 0.8128 0.8128)
			(drill 0.508)
			(layers "*.Cu" "*.Mask")
			(remove_unused_layers no)
			(net "P12V_MEZZ_B2")
		)
		(pad "J1" thru_hole circle
			(at 0 12.6 180)
			(size 0.8128 0.8128)
			(drill 0.508)
			(layers "*.Cu" "*.Mask")
			(remove_unused_layers no)
			(net "PCIE_B2T_B2_TX_DP<7>")
		)
		(pad "J2" thru_hole circle
			(at 2.000001 12.5 180)
			(size 0.8128 0.8128)
			(drill 0.508)
			(layers "*.Cu" "*.Mask")
			(remove_unused_layers no)
			(net "GND")
		)
		(pad "J3" thru_hole circle
			(at 4 12.6 180)
			(size 0.8128 0.8128)
			(drill 0.508)
			(layers "*.Cu" "*.Mask")
			(remove_unused_layers no)
			(net "PCIE_B2T_B2_TX_DP<5>")
		)
		(pad "J4" thru_hole circle
			(at 6.000001 12.5 180)
			(size 0.8128 0.8128)
			(drill 0.508)
			(layers "*.Cu" "*.Mask")
			(remove_unused_layers no)
			(net "GND")
		)
		(pad "J5" thru_hole circle
			(at 7.999999 12.6 180)
			(size 0.8128 0.8128)
			(drill 0.508)
			(layers "*.Cu" "*.Mask")
			(remove_unused_layers no)
			(net "PCIE_B2T_B2_TX_DP<3>")
		)
	)
)
